(kicad_pcb
	(version 20241229)
	(generator "pcbnew")
	(generator_version "9.0")
	(general
		(thickness 1.6642)
		(legacy_teardrops no)
	)
	(paper "A3")
	(title_block
		(title "PolarFire SoM")
		(date "2025-07-22")
		(rev "1.1.4")
		(company "Antmicro Ltd")
		(comment 1 "www.antmicro.com")
		(comment 9 "footprints 26-30 of 470")
	)
	(layers
		(0 "F.Cu" mixed)
		(4 "In1.Cu" power)
		(6 "In2.Cu" signal)
		(8 "In3.Cu" power)
		(10 "In4.Cu" signal)
		(12 "In5.Cu" power)
		(14 "In6.Cu" power)
		(16 "In7.Cu" signal)
		(18 "In8.Cu" power)
		(20 "In9.Cu" signal)
		(22 "In10.Cu" power)
		(24 "In11.Cu" signal)
		(26 "In12.Cu" signal)
		(2 "B.Cu" mixed)
		(9 "F.Adhes" user "F.Adhesive")
		(11 "B.Adhes" user "B.Adhesive")
		(13 "F.Paste" user)
		(15 "B.Paste" user)
		(5 "F.SilkS" user "F.Silkscreen")
		(7 "B.SilkS" user "B.Silkscreen")
		(1 "F.Mask" user)
		(3 "B.Mask" user)
		(17 "Dwgs.User" user "User.Drawings")
		(19 "Cmts.User" user "User.Comments")
		(21 "Eco1.User" user "User.Eco1")
		(23 "Eco2.User" user "User.Eco2")
		(25 "Edge.Cuts" user)
		(27 "Margin" user)
		(31 "F.CrtYd" user "F.Courtyard")
		(29 "B.CrtYd" user "B.Courtyard")
		(35 "F.Fab" user)
		(33 "B.Fab" user)
	)
	(footprint "antmicro-footprints:R_0402_1005Metric"
		(layer "F.Cu")
		(at 199.85 120.95 90)
		(descr "Resistor SMD 0402")
		(tags "resistor SMD 0402")
		(property "Reference" "R1"
			(at -0.27 1.33 90)
			(layer "F.SilkS")
			(effects
				(font
					(size 0.7 0.7)
					(thickness 0.15)
				)
				(justify left bottom)
			)
		)
		(property "Value" "R_100k_0402"
			(at -1.011843 1.772047 90)
			(layer "F.Fab")
			(hide yes)
			(effects
				(font
					(size 0.7 0.7)
					(thickness 0.15)
				)
				(justify left bottom)
			)
		)
		(property "Datasheet" "https://www.bourns.com/docs/product-datasheets/cr.pdf"
			(at 0 0 90)
			(layer "F.Fab")
			(hide yes)
			(effects
				(font
					(size 1.27 1.27)
					(thickness 0.15)
				)
			)
		)
		(property "Description" "SMD Chip Resistor, 100 kohm, ± 1%, 62.5 mW, 0402 [1005 Metric], Thick Film, General Purpose"
			(at 0 0 90)
			(layer "F.Fab")
			(hide yes)
			(effects
				(font
					(size 1.27 1.27)
					(thickness 0.15)
				)
			)
		)
		(property "Author" "Antmicro"
			(at 320.8 -78.9 0)
			(layer "F.Fab")
			(hide yes)
			(effects
				(font
					(size 1 1)
					(thickness 0.15)
				)
			)
		)
		(property "License" "Apache-2.0"
			(at 320.8 -78.9 0)
			(layer "F.Fab")
			(hide yes)
			(effects
				(font
					(size 1 1)
					(thickness 0.15)
				)
			)
		)
		(property "MPN" "CR0402-FX-1003GLF"
			(at 320.8 -78.9 0)
			(layer "F.Fab")
			(hide yes)
			(effects
				(font
					(size 1 1)
					(thickness 0.15)
				)
			)
		)
		(property "Manufacturer" "Bourns"
			(at 320.8 -78.9 0)
			(layer "F.Fab")
			(hide yes)
			(effects
				(font
					(size 1 1)
					(thickness 0.15)
				)
			)
		)
		(property "Public" ""
			(at 320.8 -78.9 0)
			(layer "F.Fab")
			(hide yes)
			(effects
				(font
					(size 1 1)
					(thickness 0.15)
				)
			)
		)
		(property "Tolerance" "1%"
			(at 320.8 -78.9 0)
			(layer "F.Fab")
			(hide yes)
			(effects
				(font
					(size 1 1)
					(thickness 0.15)
				)
			)
		)
		(property "Val" "100k"
			(at 320.8 -78.9 0)
			(layer "F.Fab")
			(hide yes)
			(effects
				(font
					(size 1 1)
					(thickness 0.15)
				)
			)
		)
		(sheetname "/Top Connector/")
		(sheetfile "top-connector.kicad_sch")
		(attr smd)
		(fp_rect
			(start -0.925 -0.47)
			(end 0.925 0.47)
			(stroke
				(width 0.05)
				(type default)
			)
			(fill no)
			(layer "F.CrtYd")
		)
		(fp_rect
			(start -0.5 -0.25)
			(end 0.5 0.25)
			(stroke
				(width 0.15)
				(type solid)
			)
			(fill no)
			(layer "F.Fab")
		)
		(fp_text user "Author: Antmicro"
			(at -0.95 4.169 90)
			(layer "F.Fab")
			(effects
				(font
					(size 0.7 0.7)
					(thickness 0.15)
				)
				(justify left bottom)
			)
		)
		(fp_text user "License: Apache-2.0"
			(at -0.95 5.169 90)
			(layer "F.Fab")
			(effects
				(font
					(size 0.7 0.7)
					(thickness 0.15)
				)
				(justify left bottom)
			)
		)
		(fp_text user "${REFERENCE}"
			(at -0.95 3.168 90)
			(layer "F.Fab")
			(effects
				(font
					(size 0.7 0.7)
					(thickness 0.15)
				)
				(justify left bottom)
			)
		)
		(pad "1" smd roundrect
			(at -0.48 0 90)
			(size 0.59 0.64)
			(layers "F.Cu" "F.Mask" "F.Paste")
			(roundrect_rratio 0.25)
			(net 50 "+3V3")
			(pintype "passive")
		)
		(pad "2" smd roundrect
			(at 0.48 0 90)
			(size 0.59 0.64)
			(layers "F.Cu" "F.Mask" "F.Paste")
			(roundrect_rratio 0.25)
			(net 34 "Net-(J1-Pad43)")
			(pintype "passive")
		)
	)
	(footprint "antmicro-footprints:TP_SMD_0.75mm"
		(layer "F.Cu")
		(at 221.73 150.5)
		(property "Reference" "TP33"
			(at 12.08 5.61 90)
			(layer "F.SilkS")
			(hide yes)
			(effects
				(font
					(size 0.7 0.7)
					(thickness 0.15)
				)
				(justify left bottom)
			)
		)
		(property "Value" "TP_0.75mm_SMD"
			(at 0 1.2 0)
			(layer "F.Fab")
			(hide yes)
			(effects
				(font
					(size 0.7 0.7)
					(thickness 0.15)
				)
				(justify left bottom)
			)
		)
		(property "Description" "SMT test point"
			(at 0 0 0)
			(layer "F.Fab")
			(hide yes)
			(effects
				(font
					(size 1.27 1.27)
					(thickness 0.15)
				)
			)
		)
		(property "Author" "Antmicro"
			(at 0 0 0)
			(layer "F.Fab")
			(hide yes)
			(effects
				(font
					(size 1 1)
					(thickness 0.15)
				)
			)
		)
		(property "License" "Apache-2.0"
			(at 0 0 0)
			(layer "F.Fab")
			(hide yes)
			(effects
				(font
					(size 1 1)
					(thickness 0.15)
				)
			)
		)
		(property "MPN" ""
			(at 0 0 0)
			(layer "F.Fab")
			(hide yes)
			(effects
				(font
					(size 1 1)
					(thickness 0.15)
				)
			)
		)
		(property "Manufacturer" ""
			(at 0 0 0)
			(layer "F.Fab")
			(hide yes)
			(effects
				(font
					(size 1 1)
					(thickness 0.15)
				)
			)
		)
		(property "Public" "False"
			(at 0 0 0)
			(layer "F.Fab")
			(hide yes)
			(effects
				(font
					(size 1 1)
					(thickness 0.15)
				)
			)
		)
		(sheetname "/WiFi_Bluetooth/")
		(sheetfile "wifi_bt.kicad_sch")
		(attr exclude_from_pos_files exclude_from_bom)
		(fp_circle
			(center 0 0)
			(end 0.475 0)
			(stroke
				(width 0.05)
				(type default)
			)
			(fill no)
			(layer "F.CrtYd")
		)
		(fp_text user "License: Apache-2.0"
			(at -0.4 5.101 0)
			(layer "F.Fab")
			(effects
				(font
					(size 0.7 0.7)
					(thickness 0.15)
				)
				(justify left bottom)
			)
		)
		(fp_text user "${REFERENCE}"
			(at -0.4 2.7 0)
			(layer "F.Fab")
			(effects
				(font
					(size 0.7 0.7)
					(thickness 0.15)
				)
				(justify left bottom)
			)
		)
		(fp_text user "Author: Antmicro"
			(at -0.4 3.901 0)
			(layer "F.Fab")
			(effects
				(font
					(size 0.7 0.7)
					(thickness 0.15)
				)
				(justify left bottom)
			)
		)
		(pad "1" smd circle
			(at 0 0)
			(size 0.75 0.75)
			(layers "F.Cu" "F.Mask")
			(net 530 "Net-(U26A-GPIO_1)")
			(pinfunction "1")
			(pintype "passive")
		)
	)
	(footprint "antmicro-footprints:Oscillator_SMD_Microchip_DSC1103DI2_2.5x2x0.85mm"
		(layer "F.Cu")
		(at 222.8 122.9 180)
		(tags "DSC1123DI2-125.0000 ")
		(property "Reference" "Y3"
			(at -2.12 -0.04 90)
			(unlocked yes)
			(layer "F.SilkS")
			(effects
				(font
					(size 0.7 0.7)
					(thickness 0.15)
				)
				(justify left bottom)
			)
		)
		(property "Value" "Oscillator_125MHz_DSC1103DI2"
			(at 2.75 1.75 180)
			(unlocked yes)
			(layer "F.Fab")
			(hide yes)
			(effects
				(font
					(size 0.7 0.7)
					(thickness 0.15)
				)
				(justify left bottom)
			)
		)
		(property "Datasheet" "https://ww1.microchip.com/downloads/aemDocuments/documents/TCG/ProductDocuments/DataSheets/DSC1103-23-Low-Jitter-Precision-LVDS-Oscillator-DS20005745C.pdf"
			(at 0 0 180)
			(layer "F.Fab")
			(hide yes)
			(effects
				(font
					(size 1.27 1.27)
					(thickness 0.15)
				)
			)
		)
		(property "Description" "125 MHz XO (Standard) LVDS Oscillator 3.3V Enable/Disable 6-SMD, No Lead"
			(at 0 0 180)
			(layer "F.Fab")
			(hide yes)
			(effects
				(font
					(size 1.27 1.27)
					(thickness 0.15)
				)
			)
		)
		(property "Author" "Antmicro"
			(at 445.6 245.8 0)
			(layer "F.Fab")
			(hide yes)
			(effects
				(font
					(size 1 1)
					(thickness 0.15)
				)
			)
		)
		(property "License" "Apache-2.0"
			(at 445.6 245.8 0)
			(layer "F.Fab")
			(hide yes)
			(effects
				(font
					(size 1 1)
					(thickness 0.15)
				)
			)
		)
		(property "MPN" "DSC1103DI2-125.0000"
			(at 445.6 245.8 0)
			(layer "F.Fab")
			(hide yes)
			(effects
				(font
					(size 1 1)
					(thickness 0.15)
				)
			)
		)
		(property "Manufacturer" "Microchip Technology"
			(at 445.6 245.8 0)
			(layer "F.Fab")
			(hide yes)
			(effects
				(font
					(size 1 1)
					(thickness 0.15)
				)
			)
		)
		(property "Public" ""
			(at 445.6 245.8 0)
			(layer "F.Fab")
			(hide yes)
			(effects
				(font
					(size 1 1)
					(thickness 0.15)
				)
			)
		)
		(property "Val" "125 MHz"
			(at 445.6 245.8 0)
			(layer "F.Fab")
			(hide yes)
			(effects
				(font
					(size 1 1)
					(thickness 0.15)
				)
			)
		)
		(sheetname "/FPGA MSS/")
		(sheetfile "fpga-mss.kicad_sch")
		(attr smd)
		(fp_circle
			(center -1.7 -0.825)
			(end -1.65 -0.825)
			(stroke
				(width 0.15)
				(type solid)
			)
			(fill yes)
			(layer "F.SilkS")
		)
		(fp_rect
			(start -1.25 -1.35)
			(end 1.25 1.35)
			(stroke
				(width 0.05)
				(type solid)
			)
			(fill no)
			(layer "F.CrtYd")
		)
		(fp_line
			(start 1 1.25)
			(end 1 -1.25)
			(stroke
				(width 0.15)
				(type solid)
			)
			(layer "F.Fab")
		)
		(fp_line
			(start 1 -1.25)
			(end -1 -1.25)
			(stroke
				(width 0.15)
				(type solid)
			)
			(layer "F.Fab")
		)
		(fp_line
			(start -1 1.25)
			(end 1 1.25)
			(stroke
				(width 0.15)
				(type solid)
			)
			(layer "F.Fab")
		)
		(fp_line
			(start -1 -1.25)
			(end -1 1.25)
			(stroke
				(width 0.15)
				(type solid)
			)
			(layer "F.Fab")
		)
		(fp_arc
			(start 0.305 -1.25)
			(mid 0 -0.945)
			(end -0.305 -1.25)
			(stroke
				(width 0.15)
				(type solid)
			)
			(layer "F.Fab")
		)
		(fp_circle
			(center -0.3 -0.825)
			(end -0.3 -0.825)
			(stroke
				(width 0.15)
				(type solid)
			)
			(fill no)
			(layer "F.Fab")
		)
		(fp_text user "Author: Antmicro"
			(at -1.75 4.95 180)
			(layer "F.Fab")
			(effects
				(font
					(size 0.7 0.7)
					(thickness 0.15)
				)
				(justify left bottom)
			)
		)
		(fp_text user "License: Apache-2.0"
			(at -1.75 6.15 180)
			(layer "F.Fab")
			(effects
				(font
					(size 0.7 0.7)
					(thickness 0.15)
				)
				(justify left bottom)
			)
		)
		(fp_text user "${REFERENCE}"
			(at -1.75 3.75 180)
			(unlocked yes)
			(layer "F.Fab")
			(effects
				(font
					(size 0.7 0.7)
					(thickness 0.15)
				)
				(justify left bottom)
			)
		)
		(pad "1" smd rect
			(at -0.725 -0.825 180)
			(size 0.85 0.65)
			(layers "F.Cu" "F.Mask" "F.Paste")
			(net 50 "+3V3")
			(pinfunction "EN")
			(pintype "input")
		)
		(pad "2" smd oval
			(at -0.725 0 180)
			(size 0.85 0.25)
			(layers "F.Cu" "F.Mask" "F.Paste")
			(net 575 "unconnected-(Y3-NC-Pad2)")
			(pinfunction "NC")
			(pintype "no_connect")
		)
		(pad "3" smd rect
			(at -0.725 0.825 180)
			(size 0.85 0.65)
			(layers "F.Cu" "F.Mask" "F.Paste")
			(net 417 "GND")
			(pinfunction "GND")
			(pintype "power_in")
		)
		(pad "4" smd rect
			(at 0.725 0.825 180)
			(size 0.85 0.65)
			(layers "F.Cu" "F.Mask" "F.Paste")
			(net 301 "/FPGA MSS/MSS_CLK_P")
			(pinfunction "OUT+")
			(pintype "output")
		)
		(pad "5" smd oval
			(at 0.725 0 180)
			(size 0.85 0.25)
			(layers "F.Cu" "F.Mask" "F.Paste")
			(net 302 "/FPGA MSS/MSS_CLK_N")
			(pinfunction "OUT-")
			(pintype "output")
		)
		(pad "6" smd rect
			(at 0.725 -0.825 180)
			(size 0.85 0.65)
			(layers "F.Cu" "F.Mask" "F.Paste")
			(net 50 "+3V3")
			(pinfunction "VCC")
			(pintype "power_in")
		)
	)
	(footprint "antmicro-footprints:FB_0402_1005Metric"
		(layer "F.Cu")
		(at 208.085 147.775)
		(descr "Ferrite Bead SMD 0402")
		(tags "ferrite bead SMD 0402")
		(property "Reference" "FB9"
			(at -4.16 6.54 90)
			(layer "F.SilkS")
			(effects
				(font
					(size 0.7 0.7)
					(thickness 0.15)
				)
				(justify left bottom)
			)
		)
		(property "Value" "FB_120Z_1.2A_TDK-MPZ_0402"
			(at 0 1.4 0)
			(layer "F.Fab")
			(hide yes)
			(effects
				(font
					(size 0.7 0.7)
					(thickness 0.15)
				)
				(justify left bottom)
			)
		)
		(property "Datasheet" "https://product.tdk.com/en/search/emc/emc/beads/info?part_no=MPZ1005S121CT000"
			(at 0 0 0)
			(layer "F.Fab")
			(hide yes)
			(effects
				(font
					(size 1.27 1.27)
					(thickness 0.15)
				)
			)
		)
		(property "Description" "Ferrite Bead, 0402 [1005 Metric], 120 ohm, 1.2A, MPZ, 0.06 ohm, ± 25%, DC Power line"
			(at 0 0 0)
			(layer "F.Fab")
			(hide yes)
			(effects
				(font
					(size 1.27 1.27)
					(thickness 0.15)
				)
			)
		)
		(property "Author" "Antmicro"
			(at 0 0 0)
			(layer "F.Fab")
			(hide yes)
			(effects
				(font
					(size 1 1)
					(thickness 0.15)
				)
			)
		)
		(property "Current" ""
			(at 0 0 0)
			(layer "F.Fab")
			(hide yes)
			(effects
				(font
					(size 1 1)
					(thickness 0.15)
				)
			)
		)
		(property "License" "Apache-2.0"
			(at 0 0 0)
			(layer "F.Fab")
			(hide yes)
			(effects
				(font
					(size 1 1)
					(thickness 0.15)
				)
			)
		)
		(property "MPN" "MPZ1005S121CT000"
			(at 0 0 0)
			(layer "F.Fab")
			(hide yes)
			(effects
				(font
					(size 1 1)
					(thickness 0.15)
				)
			)
		)
		(property "Manufacturer" "TDK"
			(at 0 0 0)
			(layer "F.Fab")
			(hide yes)
			(effects
				(font
					(size 1 1)
					(thickness 0.15)
				)
			)
		)
		(property "Public" ""
			(at 0 0 0)
			(layer "F.Fab")
			(hide yes)
			(effects
				(font
					(size 1 1)
					(thickness 0.15)
				)
			)
		)
		(property "Val" "120Z/1.2A"
			(at 0 0 0)
			(layer "F.Fab")
			(hide yes)
			(effects
				(font
					(size 1 1)
					(thickness 0.15)
				)
			)
		)
		(sheetname "/MIPI CrossLink/")
		(sheetfile "crosslink.kicad_sch")
		(attr smd)
		(fp_rect
			(start -0.925 -0.47)
			(end 0.925 0.47)
			(stroke
				(width 0.05)
				(type default)
			)
			(fill no)
			(layer "F.CrtYd")
		)
		(fp_rect
			(start -0.5 -0.25)
			(end 0.5 0.25)
			(stroke
				(width 0.15)
				(type solid)
			)
			(fill no)
			(layer "F.Fab")
		)
		(fp_text user "Author: Antmicro"
			(at -0.95 4.169 0)
			(layer "F.Fab")
			(effects
				(font
					(size 0.7 0.7)
					(thickness 0.15)
				)
				(justify left bottom)
			)
		)
		(fp_text user "License: Apache-2.0"
			(at -0.95 5.169 0)
			(layer "F.Fab")
			(effects
				(font
					(size 0.7 0.7)
					(thickness 0.15)
				)
				(justify left bottom)
			)
		)
		(fp_text user "${REFERENCE}"
			(at -0.95 3.168 0)
			(layer "F.Fab")
			(effects
				(font
					(size 0.7 0.7)
					(thickness 0.15)
				)
				(justify left bottom)
			)
		)
		(pad "1" smd roundrect
			(at -0.48 0)
			(size 0.59 0.64)
			(layers "F.Cu" "F.Mask" "F.Paste")
			(roundrect_rratio 0.25)
			(net 176 "/MIPI CrossLink/CL_VCC")
			(pintype "passive")
		)
		(pad "2" smd roundrect
			(at 0.48 0)
			(size 0.59 0.64)
			(layers "F.Cu" "F.Mask" "F.Paste")
			(roundrect_rratio 0.25)
			(net 96 "+1V2")
			(pintype "passive")
		)
	)
	(footprint "antmicro-footprints:TP_SMD_0.75mm"
		(layer "F.Cu")
		(at 223.635 149.23)
		(property "Reference" "TP15"
			(at 13.305 5.98 90)
			(layer "F.SilkS")
			(hide yes)
			(effects
				(font
					(size 0.7 0.7)
					(thickness 0.15)
				)
				(justify left bottom)
			)
		)
		(property "Value" "TP_0.75mm_SMD"
			(at 0 1.2 0)
			(layer "F.Fab")
			(hide yes)
			(effects
				(font
					(size 0.7 0.7)
					(thickness 0.15)
				)
				(justify left bottom)
			)
		)
		(property "Description" "SMT test point"
			(at 0 0 0)
			(layer "F.Fab")
			(hide yes)
			(effects
				(font
					(size 1.27 1.27)
					(thickness 0.15)
				)
			)
		)
		(property "Author" "Antmicro"
			(at 0 0 0)
			(layer "F.Fab")
			(hide yes)
			(effects
				(font
					(size 1 1)
					(thickness 0.15)
				)
			)
		)
		(property "License" "Apache-2.0"
			(at 0 0 0)
			(layer "F.Fab")
			(hide yes)
			(effects
				(font
					(size 1 1)
					(thickness 0.15)
				)
			)
		)
		(property "MPN" ""
			(at 0 0 0)
			(layer "F.Fab")
			(hide yes)
			(effects
				(font
					(size 1 1)
					(thickness 0.15)
				)
			)
		)
		(property "Manufacturer" ""
			(at 0 0 0)
			(layer "F.Fab")
			(hide yes)
			(effects
				(font
					(size 1 1)
					(thickness 0.15)
				)
			)
		)
		(property "Public" "False"
			(at 0 0 0)
			(layer "F.Fab")
			(hide yes)
			(effects
				(font
					(size 1 1)
					(thickness 0.15)
				)
			)
		)
		(sheetname "/WiFi_Bluetooth/")
		(sheetfile "wifi_bt.kicad_sch")
		(attr exclude_from_pos_files exclude_from_bom)
		(fp_circle
			(center 0 0)
			(end 0.475 0)
			(stroke
				(width 0.05)
				(type default)
			)
			(fill no)
			(layer "F.CrtYd")
		)
		(fp_text user "${REFERENCE}"
			(at -0.4 2.7 0)
			(layer "F.Fab")
			(effects
				(font
					(size 0.7 0.7)
					(thickness 0.15)
				)
				(justify left bottom)
			)
		)
		(fp_text user "Author: Antmicro"
			(at -0.4 3.901 0)
			(layer "F.Fab")
			(effects
				(font
					(size 0.7 0.7)
					(thickness 0.15)
				)
				(justify left bottom)
			)
		)
		(fp_text user "License: Apache-2.0"
			(at -0.4 5.101 0)
			(layer "F.Fab")
			(effects
				(font
					(size 0.7 0.7)
					(thickness 0.15)
				)
				(justify left bottom)
			)
		)
		(pad "1" smd circle
			(at 0 0)
			(size 0.75 0.75)
			(layers "F.Cu" "F.Mask")
			(net 520 "Net-(U26A-BT_PCM_SYNC)")
			(pinfunction "1")
			(pintype "passive")
		)
	)
)
